(kicad_pcb
	(version 20260206)
	(generator "pcbnew")
	(generator_version "10.0")
	(general
		(thickness 1.6)
		(legacy_teardrops no)
	)
	(paper "A4")
	(title_block
		(title "baseboard — 13948-1b.1110WZS1818.brd")
		(comment 1 "Honey Badger (Wiwynn) / footprints 1399-1403 of 2523")
	)
	(layers
		(0 "F.Cu" signal "TOP")
		(4 "In1.Cu" signal "L2GND")
		(6 "In2.Cu" signal "L3")
		(8 "In3.Cu" signal "L4VCC")
		(10 "In4.Cu" signal "L5VCC")
		(12 "In5.Cu" signal "L6")
		(14 "In6.Cu" signal "L7GND")
		(2 "B.Cu" signal "BOTTOM")
		(9 "F.Adhes" user "F.Adhesive")
		(11 "B.Adhes" user "B.Adhesive")
		(13 "F.Paste" user "Package Geometry/Pastemask Top")
		(15 "B.Paste" user "Package Geometry/Pastemask Bottom")
		(5 "F.SilkS" user "Ref Des/Silkscreen Top")
		(7 "B.SilkS" user "Ref Des/Silkscreen Bottom")
		(1 "F.Mask" user "Board Geometry/Soldermask Top")
		(3 "B.Mask" user "Board Geometry/Soldermask Bottom")
		(17 "Dwgs.User" user "User.Drawings")
		(19 "Cmts.User" user "User.Comments")
		(21 "Eco1.User" user "User.Eco1")
		(23 "Eco2.User" user "User.Eco2")
		(25 "Edge.Cuts" user "Board Geometry/Outline")
		(27 "Margin" user)
		(31 "F.CrtYd" user "Package Geometry/Place Bound Top")
		(29 "B.CrtYd" user "Package Geometry/Place Bound Bottom")
		(35 "F.Fab" user "Ref Des/Assembly Top")
		(33 "B.Fab" user "Ref Des/Assembly Bottom")
	)
	(footprint ""
		(layer "F.Cu")
		(at 186.309 -51.054 180)
		(property "Reference" "U45"
			(at 0 0 180)
			(layer "F.SilkS")
			(hide yes)
			(effects
				(font
					(size 1.27 1.27)
				)
			)
		)
		(property "Value" "SN74LVC1G11DCKR-GP"
			(at 0.0508 -11.5824 180)
			(unlocked yes)
			(layer "F.Fab")
			(hide yes)
			(effects
				(font
					(size 1.016 1.016)
					(thickness 0.1524)
				)
			)
		)
		(property "Device Type" "UMT6H44"
			(at 0.0508 -13.1572 180)
			(unlocked yes)
			(layer "F.Fab")
			(hide yes)
			(effects
				(font
					(size 1.016 1.016)
					(thickness 0.1524)
				)
			)
		)
		(duplicate_pad_numbers_are_jumpers no)
		(fp_line
			(start 1.524 0.36449)
			(end -1.27 0.36449)
			(stroke
				(width 0.1524)
				(type default)
			)
			(layer "F.SilkS")
		)
		(fp_line
			(start 1.524 -0.36449)
			(end 1.524 0.36449)
			(stroke
				(width 0.1524)
				(type default)
			)
			(layer "F.SilkS")
		)
		(fp_line
			(start 1.524 -0.36449)
			(end 1.524 -1.82245)
			(stroke
				(width 0.508)
				(type default)
			)
			(layer "F.SilkS")
		)
		(fp_line
			(start 1.524 -0.36449)
			(end 1.45796 -0.36449)
			(stroke
				(width 0.1524)
				(type default)
			)
			(layer "F.SilkS")
		)
		(fp_line
			(start 1.45796 -0.36449)
			(end 1.09347 0)
			(stroke
				(width 0.1524)
				(type default)
			)
			(layer "F.SilkS")
		)
		(fp_line
			(start 1.09347 0)
			(end 1.45796 0.36449)
			(stroke
				(width 0.1524)
				(type default)
			)
			(layer "F.SilkS")
		)
		(fp_line
			(start -1.27 -0.36449)
			(end 1.524 -0.36449)
			(stroke
				(width 0.1524)
				(type default)
			)
			(layer "F.SilkS")
		)
		(fp_line
			(start -1.27 -0.36449)
			(end -1.27 0.36449)
			(stroke
				(width 0.1524)
				(type default)
			)
			(layer "F.SilkS")
		)
		(fp_poly
			(pts
				(xy -0.65024 0.36449) (xy -0.65024 -0.36449) (xy 0.65024 -0.36449) (xy 0.65024 0.36449)
			)
			(stroke
				(width 0)
				(type default)
			)
			(fill yes)
			(layer "F.SilkS")
		)
		(fp_poly
			(pts
				(xy 1.016 -1.0668) (xy 1.016 1.0668) (xy -1.016 1.0668) (xy -1.016 -1.0668)
			)
			(stroke
				(width 0)
				(type default)
			)
			(fill no)
			(layer "F.CrtYd")
		)
		(fp_poly
			(pts
				(xy -1.524 1.905) (xy 1.524 1.905) (xy 1.524 -1.06426) (xy 1.016 -1.06426) (xy 1.016 1.0668) (xy -1.016 1.0668)
				(xy -1.016 -1.0668) (xy 1.524 -1.0668) (xy 1.524 -1.905) (xy -1.524 -1.905)
			)
			(stroke
				(width 0)
				(type default)
			)
			(fill no)
			(layer "F.CrtYd")
		)
		(fp_poly
			(pts
				(xy -1.524 -1.905) (xy -1.524 1.905) (xy 1.524 1.905) (xy 1.524 -1.905)
			)
			(stroke
				(width 0)
				(type default)
			)
			(fill no)
			(layer "F.Fab")
		)
		(pad "1" smd rect
			(at 0.65024 -1.02489 180)
			(size 0.4064 0.8128)
			(layers "F.Cu" "F.Mask" "F.Paste")
			(net "PRSNT_AND_2")
		)
		(pad "2" smd rect
			(at 0 -1.02489 180)
			(size 0.4064 0.8128)
			(layers "F.Cu" "F.Mask" "F.Paste")
			(net "GND")
		)
		(pad "3" smd rect
			(at -0.65024 -1.02489 180)
			(size 0.4064 0.8128)
			(layers "F.Cu" "F.Mask" "F.Paste")
			(net "PRSNT_MSB_AND_1")
		)
		(pad "4" smd rect
			(at -0.65024 1.02489 180)
			(size 0.4064 0.8128)
			(layers "F.Cu" "F.Mask" "F.Paste")
			(net "PRSNT_EN_HPIC")
		)
		(pad "5" smd rect
			(at 0 1.02489 180)
			(size 0.4064 0.8128)
			(layers "F.Cu" "F.Mask" "F.Paste")
			(net "P3V3_STBY")
		)
		(pad "6" smd rect
			(at 0.65024 1.02489 180)
			(size 0.4064 0.8128)
			(layers "F.Cu" "F.Mask" "F.Paste")
			(net "MSB_PRSNT_AND_3")
		)
	)
	(footprint ""
		(layer "F.Cu")
		(at 307.975 -193.802 180)
		(property "Reference" "R171"
			(at 0 0 180)
			(layer "F.SilkS")
			(hide yes)
			(effects
				(font
					(size 1.27 1.27)
				)
			)
		)
		(property "Value" "100KR2F-L1-GP"
			(at 0.064008 -3.993896 180)
			(unlocked yes)
			(layer "F.Fab")
			(hide yes)
			(effects
				(font
					(size 1.016 1.016)
					(thickness 0.1524)
				)
			)
		)
		(property "Device Type" "R402H16"
			(at 0.064008 -5.517896 180)
			(unlocked yes)
			(layer "F.Fab")
			(hide yes)
			(effects
				(font
					(size 1.016 1.016)
					(thickness 0.1524)
				)
			)
		)
		(duplicate_pad_numbers_are_jumpers no)
		(fp_line
			(start 0.508 -0.9398)
			(end -0.508 -0.9398)
			(stroke
				(width 0.1524)
				(type default)
			)
			(layer "F.SilkS")
		)
		(fp_line
			(start -0.508 -0.9398)
			(end -0.508 0.9398)
			(stroke
				(width 0.1524)
				(type default)
			)
			(layer "F.SilkS")
		)
		(fp_rect
			(start -0.508 0.9398)
			(end 0.508 -0.9398)
			(stroke
				(width 0)
				(type default)
			)
			(fill no)
			(layer "F.CrtYd")
		)
		(fp_rect
			(start -0.508 0.9398)
			(end 0.508 -0.9398)
			(stroke
				(width 0)
				(type default)
			)
			(fill no)
			(layer "F.Fab")
		)
		(pad "1" smd custom
			(at 0 -0.4445 180)
			(size 0.1397 0.1397)
			(layers "F.Cu" "F.Mask" "F.Paste")
			(net "P3V3_STBY")
			(options
				(clearance outline)
				(anchor circle)
			)
			(primitives
				(gr_poly
					(pts
						(arc
							(start -0.1778 -0.2794)
							(mid -0.249642 -0.249642)
							(end -0.2794 -0.1778)
						)
						(arc
							(start -0.2794 0.1778)
							(mid -0.249642 0.249642)
							(end -0.1778 0.2794)
						)
						(arc
							(start 0.1778 0.2794)
							(mid 0.249642 0.249642)
							(end 0.2794 0.1778)
						)
						(arc
							(start 0.2794 -0.1778)
							(mid 0.249642 -0.249642)
							(end 0.1778 -0.2794)
						)
					)
					(width 0)
					(fill yes)
				)
			)
		)
		(pad "2" smd custom
			(at 0 0.4445 180)
			(size 0.1397 0.1397)
			(layers "F.Cu" "F.Mask" "F.Paste")
			(net "LED_DR_LED1")
			(options
				(clearance outline)
				(anchor circle)
			)
			(primitives
				(gr_poly
					(pts
						(arc
							(start -0.1778 -0.2794)
							(mid -0.249642 -0.249642)
							(end -0.2794 -0.1778)
						)
						(arc
							(start -0.2794 0.1778)
							(mid -0.249642 0.249642)
							(end -0.1778 0.2794)
						)
						(arc
							(start 0.1778 0.2794)
							(mid 0.249642 0.249642)
							(end 0.2794 0.1778)
						)
						(arc
							(start 0.2794 -0.1778)
							(mid 0.249642 -0.249642)
							(end 0.1778 -0.2794)
						)
					)
					(width 0)
					(fill yes)
				)
			)
		)
	)
	(footprint ""
		(layer "F.Cu")
		(at 56.388 -218.059 90)
		(property "Reference" "U2"
			(at 0 0 90)
			(layer "F.SilkS")
			(hide yes)
			(effects
				(font
					(size 1.27 1.27)
				)
			)
		)
		(property "Value" "ADM1278-2ACPZ-RL-1-GP"
			(at -4.7625 -7.4422 90)
			(unlocked yes)
			(layer "F.Fab")
			(hide yes)
			(effects
				(font
					(size 1.016 1.016)
					(thickness 0.1524)
				)
			)
		)
		(property "Device Type" "QFN32-G3D45-UH32"
			(at -4.7625 -8.9662 90)
			(unlocked yes)
			(layer "F.Fab")
			(hide yes)
			(effects
				(font
					(size 1.016 1.016)
					(thickness 0.1524)
				)
			)
		)
		(duplicate_pad_numbers_are_jumpers no)
		(fp_line
			(start -0.250698 -3.7973)
			(end -0.250698 -3.2893)
			(stroke
				(width 0.1524)
				(type default)
			)
			(layer "F.SilkS")
		)
		(fp_line
			(start -3.5179 -3.5179)
			(end -2.2479 -3.5179)
			(stroke
				(width 0.1524)
				(type default)
			)
			(layer "F.SilkS")
		)
		(fp_line
			(start -3.5179 -2.2479)
			(end -3.5179 -3.5179)
			(stroke
				(width 0.1524)
				(type default)
			)
			(layer "F.SilkS")
		)
		(fp_line
			(start -4.0513 -1.24968)
			(end -3.2893 -1.24968)
			(stroke
				(width 0.1524)
				(type default)
			)
			(layer "F.SilkS")
		)
		(fp_line
			(start 4.0513 -0.749808)
			(end 3.2893 -0.749808)
			(stroke
				(width 0.1524)
				(type default)
			)
			(layer "F.SilkS")
		)
		(fp_line
			(start -3.7973 1.24968)
			(end -3.2893 1.24968)
			(stroke
				(width 0.1524)
				(type default)
			)
			(layer "F.SilkS")
		)
		(fp_line
			(start 3.7973 1.749552)
			(end 3.2893 1.749552)
			(stroke
				(width 0.1524)
				(type default)
			)
			(layer "F.SilkS")
		)
		(fp_line
			(start 3.5179 2.2479)
			(end 3.5179 3.5179)
			(stroke
				(width 0.1524)
				(type default)
			)
			(layer "F.SilkS")
		)
		(fp_line
			(start -3.5179 2.2479)
			(end -3.5179 3.5179)
			(stroke
				(width 0.1524)
				(type default)
			)
			(layer "F.SilkS")
		)
		(fp_line
			(start 3.5179 3.5179)
			(end 2.2479 3.5179)
			(stroke
				(width 0.1524)
				(type default)
			)
			(layer "F.SilkS")
		)
		(fp_line
			(start -3.5179 3.5179)
			(end -2.2479 3.5179)
			(stroke
				(width 0.1524)
				(type default)
			)
			(layer "F.SilkS")
		)
		(fp_line
			(start -0.250698 4.0513)
			(end -0.250698 3.2893)
			(stroke
				(width 0.1524)
				(type default)
			)
			(layer "F.SilkS")
		)
		(fp_poly
			(pts
				(xy 2.2479 -3.5179) (xy 3.5179 -2.2479) (xy 3.5179 -3.5179)
			)
			(stroke
				(width 0)
				(type default)
			)
			(fill yes)
			(layer "F.SilkS")
		)
		(fp_rect
			(start -2.5019 2.5019)
			(end 2.5019 -2.5019)
			(stroke
				(width 0)
				(type default)
			)
			(fill no)
			(layer "F.CrtYd")
		)
		(fp_poly
			(pts
				(xy -3.5179 3.5179) (xy -3.5179 -3.5179) (xy 3.5179 -3.5179) (xy 3.5179 3.5179) (xy -2.49682 3.5179)
				(xy -2.49682 2.5019) (xy 2.5019 2.5019) (xy 2.5019 -2.5019) (xy -2.5019 -2.5019) (xy -2.5019 3.5179)
			)
			(stroke
				(width 0)
				(type default)
			)
			(fill no)
			(layer "F.CrtYd")
		)
		(fp_rect
			(start -3.5179 3.5179)
			(end 3.5179 -3.5179)
			(stroke
				(width 0)
				(type default)
			)
			(fill no)
			(layer "F.Fab")
		)
		(pad "1" smd rect
			(at 1.75006 -2.5527 90)
			(size 0.3048 0.9144)
			(layers "F.Cu" "F.Mask" "F.Paste")
			(net "MB0_PSET_R")
		)
		(pad "2" smd rect
			(at 1.249934 -2.4765 90)
			(size 0.3048 1.0668)
			(layers "F.Cu" "F.Mask" "F.Paste")
			(net "MB0_VCAP_R")
		)
		(pad "3" smd rect
			(at 0.750062 -2.4765 90)
			(size 0.3048 1.0668)
			(layers "F.Cu" "F.Mask" "F.Paste")
			(net "MB0_ISET_R")
		)
		(pad "4" smd rect
			(at 0.249936 -2.4765 90)
			(size 0.3048 1.0668)
			(layers "F.Cu" "F.Mask" "F.Paste")
			(net "MB0_ISTART_R")
		)
		(pad "5" smd rect
			(at -0.249936 -2.4765 90)
			(size 0.3048 1.0668)
			(layers "F.Cu" "F.Mask" "F.Paste")
			(net "MB0_TIME_R")
		)
		(pad "6" smd rect
			(at -0.750062 -2.4765 90)
			(size 0.3048 1.0668)
			(layers "F.Cu" "F.Mask" "F.Paste")
			(net "Net_88")
		)
		(pad "7" smd rect
			(at -1.249934 -2.4765 90)
			(size 0.3048 1.0668)
			(layers "F.Cu" "F.Mask" "F.Paste")
			(net "MB0_CM_ADR1_R")
		)
		(pad "8" smd rect
			(at -1.75006 -2.5527 90)
			(size 0.3048 0.9144)
			(layers "F.Cu" "F.Mask" "F.Paste")
			(net "MB0_CM_ADR2_R")
		)
		(pad "9" smd rect
			(at -2.5527 -1.75006 90)
			(size 0.9144 0.3048)
			(layers "F.Cu" "F.Mask" "F.Paste")
			(net "MB0_SPISS_PD")
		)
		(pad "10" smd rect
			(at -2.4765 -1.249934 90)
			(size 1.0668 0.3048)
			(layers "F.Cu" "F.Mask" "F.Paste")
			(net "Net_92")
		)
		(pad "11" smd rect
			(at -2.4765 -0.750062 90)
			(size 1.0668 0.3048)
			(layers "F.Cu" "F.Mask" "F.Paste")
			(net "Net_91")
		)
		(pad "12" smd rect
			(at -2.4765 -0.249936 90)
			(size 1.0668 0.3048)
			(layers "F.Cu" "F.Mask" "F.Paste")
			(net "MB0_HS_ENABLE")
		)
		(pad "13" smd rect
			(at -2.4765 0.249936 90)
			(size 1.0668 0.3048)
			(layers "F.Cu" "F.Mask" "F.Paste")
			(net "Net_90")
		)
		(pad "14" smd rect
			(at -2.4765 0.750062 90)
			(size 1.0668 0.3048)
			(layers "F.Cu" "F.Mask" "F.Paste")
			(net "Net_89")
		)
		(pad "15" smd rect
			(at -2.4765 1.249934 90)
			(size 1.0668 0.3048)
			(layers "F.Cu" "F.Mask" "F.Paste")
			(net "HSW_SDA_2")
		)
		(pad "16" smd rect
			(at -2.5527 1.75006 90)
			(size 0.9144 0.3048)
			(layers "F.Cu" "F.Mask" "F.Paste")
			(net "HSW_SCL_2")
		)
		(pad "17" smd rect
			(at -1.75006 2.5527 90)
			(size 0.3048 0.9144)
			(layers "F.Cu" "F.Mask" "F.Paste")
			(net "MB0_RETRY_R")
		)
		(pad "18" smd rect
			(at -1.249934 2.4765 90)
			(size 0.3048 1.0668)
			(layers "F.Cu" "F.Mask" "F.Paste")
			(net "MB0_P12V_PWRGOOD")
		)
		(pad "19" smd rect
			(at -0.750062 2.4765 90)
			(size 0.3048 1.0668)
			(layers "F.Cu" "F.Mask" "F.Paste")
			(net "Net_93")
		)
		(pad "20" smd rect
			(at -0.249936 2.4765 90)
			(size 0.3048 1.0668)
			(layers "F.Cu" "F.Mask" "F.Paste")
			(net "MB0_CM_VOUT_R")
		)
		(pad "21" smd rect
			(at 0.249936 2.4765 90)
			(size 0.3048 1.0668)
			(layers "F.Cu" "F.Mask" "F.Paste")
			(net "MB0_P12V_PWGIN_R")
		)
		(pad "22" smd rect
			(at 0.750062 2.4765 90)
			(size 0.3048 1.0668)
			(layers "F.Cu" "F.Mask" "F.Paste")
			(net "AGND_CURRENT_MON")
		)
		(pad "23" smd rect
			(at 1.249934 2.4765 90)
			(size 0.3048 1.0668)
			(layers "F.Cu" "F.Mask" "F.Paste")
			(net "GND")
		)
		(pad "24" smd rect
			(at 1.75006 2.5527 90)
			(size 0.3048 0.9144)
			(layers "F.Cu" "F.Mask" "F.Paste")
			(net "MB0_CM_GATE")
		)
		(pad "25" smd rect
			(at 2.5527 1.75006 90)
			(size 0.9144 0.3048)
			(layers "F.Cu" "F.Mask" "F.Paste")
			(net "MB0_TEMP")
		)
		(pad "26" smd rect
			(at 2.4765 1.249934 90)
			(size 1.0668 0.3048)
			(layers "F.Cu" "F.Mask" "F.Paste")
			(net "MB0_CM_SENSE_N")
		)
		(pad "27" smd rect
			(at 2.4765 0.750062 90)
			(size 1.0668 0.3048)
			(layers "F.Cu" "F.Mask" "F.Paste")
			(net "MB0_P12V_MAIN_R")
		)
		(pad "28" smd rect
			(at 2.4765 0.249936 90)
			(size 1.0668 0.3048)
			(layers "F.Cu" "F.Mask" "F.Paste")
			(net "P12V_PCIE")
		)
		(pad "29" smd rect
			(at 2.4765 -0.249936 90)
			(size 1.0668 0.3048)
			(layers "F.Cu" "F.Mask" "F.Paste")
			(net "MB0_CM_SENSE_P")
		)
		(pad "30" smd rect
			(at 2.4765 -0.750062 90)
			(size 1.0668 0.3048)
			(layers "F.Cu" "F.Mask" "F.Paste")
			(net "MB0_VCC")
		)
		(pad "31" smd rect
			(at 2.4765 -1.249934 90)
			(size 1.0668 0.3048)
			(layers "F.Cu" "F.Mask" "F.Paste")
			(net "MB0_CM_UV_R")
		)
		(pad "32" smd rect
			(at 2.5527 -1.75006 90)
			(size 0.9144 0.3048)
			(layers "F.Cu" "F.Mask" "F.Paste")
			(net "MB0_CM_OV_R")
		)
		(pad "33" smd rect
			(at 0 0 90)
			(size 3.4544 3.4544)
			(layers "F.Cu" "F.Mask" "F.Paste")
			(net "AGND_CURRENT_MON")
		)
	)
	(footprint ""
		(layer "F.Cu")
		(at 339.471 -34.798)
		(property "Reference" "R487"
			(at 0 0 0)
			(layer "F.SilkS")
			(hide yes)
			(effects
				(font
					(size 1.27 1.27)
				)
			)
		)
		(property "Value" "0R2J-2-GP"
			(at 0.064008 -3.993896 0)
			(unlocked yes)
			(layer "F.Fab")
			(hide yes)
			(effects
				(font
					(size 1.016 1.016)
					(thickness 0.1524)
				)
			)
		)
		(property "Device Type" "R402H16"
			(at 0.064008 -5.517896 0)
			(unlocked yes)
			(layer "F.Fab")
			(hide yes)
			(effects
				(font
					(size 1.016 1.016)
					(thickness 0.1524)
				)
			)
		)
		(duplicate_pad_numbers_are_jumpers no)
		(fp_line
			(start -0.508 -0.9398)
			(end -0.508 0.9398)
			(stroke
				(width 0.1524)
				(type default)
			)
			(layer "F.SilkS")
		)
		(fp_line
			(start 0.508 -0.9398)
			(end -0.508 -0.9398)
			(stroke
				(width 0.1524)
				(type default)
			)
			(layer "F.SilkS")
		)
		(fp_rect
			(start -0.508 0.9398)
			(end 0.508 -0.9398)
			(stroke
				(width 0)
				(type default)
			)
			(fill no)
			(layer "F.CrtYd")
		)
		(fp_rect
			(start -0.508 0.9398)
			(end 0.508 -0.9398)
			(stroke
				(width 0)
				(type default)
			)
			(fill no)
			(layer "F.Fab")
		)
		(pad "1" smd custom
			(at 0 -0.4445)
			(size 0.1397 0.1397)
			(layers "F.Cu" "F.Mask" "F.Paste")
			(net "BMC_UART_SWITCH_2")
			(options
				(clearance outline)
				(anchor circle)
			)
			(primitives
				(gr_poly
					(pts
						(arc
							(start -0.1778 -0.2794)
							(mid -0.249642 -0.249642)
							(end -0.2794 -0.1778)
						)
						(arc
							(start -0.2794 0.1778)
							(mid -0.249642 0.249642)
							(end -0.1778 0.2794)
						)
						(arc
							(start 0.1778 0.2794)
							(mid 0.249642 0.249642)
							(end 0.2794 0.1778)
						)
						(arc
							(start 0.2794 -0.1778)
							(mid 0.249642 -0.249642)
							(end 0.1778 -0.2794)
						)
					)
					(width 0)
					(fill yes)
				)
			)
		)
		(pad "2" smd custom
			(at 0 0.4445)
			(size 0.1397 0.1397)
			(layers "F.Cu" "F.Mask" "F.Paste")
			(net "BMC_CONSOLE_LED1_R")
			(options
				(clearance outline)
				(anchor circle)
			)
			(primitives
				(gr_poly
					(pts
						(arc
							(start -0.1778 -0.2794)
							(mid -0.249642 -0.249642)
							(end -0.2794 -0.1778)
						)
						(arc
							(start -0.2794 0.1778)
							(mid -0.249642 0.249642)
							(end -0.1778 0.2794)
						)
						(arc
							(start 0.1778 0.2794)
							(mid 0.249642 0.249642)
							(end 0.2794 0.1778)
						)
						(arc
							(start 0.2794 -0.1778)
							(mid 0.249642 -0.249642)
							(end 0.1778 -0.2794)
						)
					)
					(width 0)
					(fill yes)
				)
			)
		)
	)
	(footprint ""
		(layer "F.Cu")
		(at 85.452966 -80.391)
		(property "Reference" "SC1195"
			(at 0 0 0)
			(layer "F.SilkS")
			(hide yes)
			(effects
				(font
					(size 1.27 1.27)
				)
			)
		)
		(property "Value" "SC10U6D3V5KX-4GP"
			(at -0.0762 -6.1214 0)
			(unlocked yes)
			(layer "F.Fab")
			(hide yes)
			(effects
				(font
					(size 1.016 1.016)
					(thickness 0.1524)
				)
			)
		)
		(property "Device Type" "C805H58"
			(at -0.0762 -8.1534 0)
			(unlocked yes)
			(layer "F.Fab")
			(hide yes)
			(effects
				(font
					(size 1.016 1.016)
					(thickness 0.1524)
				)
			)
		)
		(duplicate_pad_numbers_are_jumpers no)
		(fp_line
			(start 0.635 0)
			(end -0.635 0)
			(stroke
				(width 0.508)
				(type default)
			)
			(layer "F.SilkS")
		)
		(fp_rect
			(start -0.9652 1.778)
			(end 0.9652 -1.778)
			(stroke
				(width 0)
				(type default)
			)
			(fill no)
			(layer "F.CrtYd")
		)
		(fp_poly
			(pts
				(xy -0.9652 -1.778) (xy 0.9652 -1.778) (xy 0.9652 1.778) (xy -0.9652 1.778)
			)
			(stroke
				(width 0)
				(type default)
			)
			(fill no)
			(layer "F.Fab")
		)
		(pad "1" smd rect
			(at 0 -0.9652)
			(size 1.397 1.143)
			(layers "F.Cu" "F.Mask" "F.Paste")
			(net "XTAL_VDDA09")
		)
		(pad "2" smd rect
			(at 0 0.9652)
			(size 1.397 1.143)
			(layers "F.Cu" "F.Mask" "F.Paste")
			(net "GND")
		)
	)
)
